# S9S_MB_2U (Grand Teton) — schematic netlist excerpt (pin names and nets, part order shuffled) for the footprints in the layout excerpt that follows; sources: Cadence DE-HDL packaged netlist, KiCad conversion of 03242023_DA0F0TMBIJ0_F0T_Motherboard_J_brd_V01_OCP.brd

R1044  Q_RES  130 1% CHIP  pkg 0402LF  page 255 : A = LED_PWRGD_CPUPWRGD_GTL ; B = P3V3_AUX
PC483_P1_8  Q_CAP  3300PF 50V 10% X7R  pkg 0402  page 288 : A = SW_P12V_PVCCIN_CPU1_FLT ; B = GND

(kicad_pcb
	(version 20260206)
	(generator "pcbnew")
	(generator_version "10.0")
	(general
		(thickness 1.6)
		(legacy_teardrops no)
	)
	(paper "A4")
	(title_block
		(title "03242023_DA0F0TMBIJ0_F0T_Motherboard_J_brd_V01_OCP.brd")
		(comment 1 "Grand Teton / footprints 1891-1892 of 6105")
	)
	(layers
		(0 "F.Cu" signal "TOP")
		(4 "In1.Cu" signal "GND")
		(6 "In2.Cu" signal "IN1")
		(8 "In3.Cu" signal "GND1")
		(10 "In4.Cu" signal "IN2")
		(12 "In5.Cu" signal "GND2")
		(14 "In6.Cu" signal "IN3")
		(16 "In7.Cu" signal "GND3")
		(18 "In8.Cu" signal "VCC")
		(20 "In9.Cu" signal "VCC1")
		(22 "In10.Cu" signal "GND4")
		(24 "In11.Cu" signal "IN4")
		(26 "In12.Cu" signal "GND5")
		(28 "In13.Cu" signal "IN5")
		(30 "In14.Cu" signal "GND6")
		(32 "In15.Cu" signal "IN6")
		(34 "In16.Cu" signal "GND7")
		(2 "B.Cu" signal "BOTTOM")
		(9 "F.Adhes" user "F.Adhesive")
		(11 "B.Adhes" user "B.Adhesive")
		(13 "F.Paste" user "Package Geometry/Pastemask Top")
		(15 "B.Paste" user "Package Geometry/Pastemask Bottom")
		(5 "F.SilkS" user "Ref Des/Silkscreen Top")
		(7 "B.SilkS" user "Ref Des/Silkscreen Bottom")
		(1 "F.Mask" user "Board Geometry/Soldermask Top")
		(3 "B.Mask" user "Board Geometry/Soldermask Bottom")
		(17 "Dwgs.User" user "User.Drawings")
		(19 "Cmts.User" user "User.Comments")
		(21 "Eco1.User" user "User.Eco1")
		(23 "Eco2.User" user "User.Eco2")
		(25 "Edge.Cuts" user "Board Geometry/Outline")
		(27 "Margin" user)
		(31 "F.CrtYd" user "Package Geometry/Place Bound Top")
		(29 "B.CrtYd" user "Package Geometry/Place Bound Bottom")
		(35 "F.Fab" user "Ref Des/Assembly Top")
		(33 "B.Fab" user "Ref Des/Assembly Bottom")
	)
	(footprint ""
		(layer "F.Cu")
		(at 142.486126 -343.018872 -90)
		(property "Reference" "PC483_P1_8"
			(at 0 0 270)
			(layer "F.SilkS")
			(hide yes)
			(effects
				(font
					(size 1.27 1.27)
				)
			)
		)
		(property "Value" ""
			(at 0 0 270)
			(layer "F.Fab")
			(effects
				(font
					(size 1.27 1.27)
				)
			)
		)
		(duplicate_pad_numbers_are_jumpers no)
		(fp_line
			(start -0.7874 0.4064)
			(end -0.7874 -0.4064)
			(stroke
				(width 0.1524)
				(type default)
			)
			(layer "F.SilkS")
		)
		(fp_line
			(start 0.7874 0.4064)
			(end -0.7874 0.4064)
			(stroke
				(width 0.1524)
				(type default)
			)
			(layer "F.SilkS")
		)
		(fp_line
			(start -0.7874 -0.4064)
			(end 0.7874 -0.4064)
			(stroke
				(width 0.1524)
				(type default)
			)
			(layer "F.SilkS")
		)
		(fp_line
			(start 0.7874 -0.4064)
			(end 0.7874 0.4064)
			(stroke
				(width 0.1524)
				(type default)
			)
			(layer "F.SilkS")
		)
		(fp_line
			(start -0.67945 0.3048)
			(end -0.67945 -0.305054)
			(stroke
				(width 0.1)
				(type default)
			)
			(layer "F.Fab")
		)
		(fp_line
			(start -0.12065 0.3048)
			(end -0.67945 0.3048)
			(stroke
				(width 0.1)
				(type default)
			)
			(layer "F.Fab")
		)
		(fp_line
			(start 0.120396 0.3048)
			(end 0.120396 0.2794)
			(stroke
				(width 0.1)
				(type default)
			)
			(layer "F.Fab")
		)
		(fp_line
			(start 0.67945 0.3048)
			(end 0.120396 0.3048)
			(stroke
				(width 0.1)
				(type default)
			)
			(layer "F.Fab")
		)
		(fp_line
			(start -0.12065 0.2794)
			(end -0.12065 0.3048)
			(stroke
				(width 0.1)
				(type default)
			)
			(layer "F.Fab")
		)
		(fp_line
			(start 0.120396 0.2794)
			(end -0.12065 0.2794)
			(stroke
				(width 0.1)
				(type default)
			)
			(layer "F.Fab")
		)
		(fp_line
			(start -0.12065 -0.2794)
			(end 0.12065 -0.2794)
			(stroke
				(width 0.1)
				(type default)
			)
			(layer "F.Fab")
		)
		(fp_line
			(start 0.12065 -0.2794)
			(end 0.12065 -0.3048)
			(stroke
				(width 0.1)
				(type default)
			)
			(layer "F.Fab")
		)
		(fp_line
			(start 0.12065 -0.3048)
			(end 0.67945 -0.3048)
			(stroke
				(width 0.1)
				(type default)
			)
			(layer "F.Fab")
		)
		(fp_line
			(start 0.67945 -0.3048)
			(end 0.67945 0.3048)
			(stroke
				(width 0.1)
				(type default)
			)
			(layer "F.Fab")
		)
		(fp_line
			(start -0.67945 -0.305054)
			(end -0.12065 -0.305054)
			(stroke
				(width 0.1)
				(type default)
			)
			(layer "F.Fab")
		)
		(fp_line
			(start -0.12065 -0.305054)
			(end -0.12065 -0.2794)
			(stroke
				(width 0.1)
				(type default)
			)
			(layer "F.Fab")
		)
		(pad "1" smd circle
			(at -0.40005 0 270)
			(size 0 0)
			(layers "F.Cu" "F.Mask" "F.Paste")
			(net "SW_P12V_PVCCIN_CPU1_FLT")
		)
		(pad "2" smd circle
			(at 0.40005 0 270)
			(size 0 0)
			(layers "F.Cu" "F.Mask" "F.Paste")
			(net "GND")
		)
	)
	(footprint ""
		(layer "F.Cu")
		(at 86.868 -65.173098 -90)
		(property "Reference" "R1044"
			(at 0 0 270)
			(layer "F.SilkS")
			(hide yes)
			(effects
				(font
					(size 1.27 1.27)
				)
			)
		)
		(property "Value" ""
			(at 0 0 270)
			(layer "F.Fab")
			(effects
				(font
					(size 1.27 1.27)
				)
			)
		)
		(duplicate_pad_numbers_are_jumpers no)
		(fp_line
			(start -0.7874 0.4064)
			(end -0.7874 -0.4064)
			(stroke
				(width 0.1524)
				(type default)
			)
			(layer "F.SilkS")
		)
		(fp_line
			(start 0.7874 0.4064)
			(end -0.7874 0.4064)
			(stroke
				(width 0.1524)
				(type default)
			)
			(layer "F.SilkS")
		)
		(fp_line
			(start -0.7874 -0.4064)
			(end 0.7874 -0.4064)
			(stroke
				(width 0.1524)
				(type default)
			)
			(layer "F.SilkS")
		)
		(fp_line
			(start 0.7874 -0.4064)
			(end 0.7874 0.4064)
			(stroke
				(width 0.1524)
				(type default)
			)
			(layer "F.SilkS")
		)
		(fp_line
			(start -0.67945 0.3048)
			(end -0.67945 -0.305054)
			(stroke
				(width 0.1)
				(type default)
			)
			(layer "F.Fab")
		)
		(fp_line
			(start -0.12065 0.3048)
			(end -0.67945 0.3048)
			(stroke
				(width 0.1)
				(type default)
			)
			(layer "F.Fab")
		)
		(fp_line
			(start 0.120396 0.3048)
			(end 0.120396 0.2794)
			(stroke
				(width 0.1)
				(type default)
			)
			(layer "F.Fab")
		)
		(fp_line
			(start 0.67945 0.3048)
			(end 0.120396 0.3048)
			(stroke
				(width 0.1)
				(type default)
			)
			(layer "F.Fab")
		)
		(fp_line
			(start -0.12065 0.2794)
			(end -0.12065 0.3048)
			(stroke
				(width 0.1)
				(type default)
			)
			(layer "F.Fab")
		)
		(fp_line
			(start 0.120396 0.2794)
			(end -0.12065 0.2794)
			(stroke
				(width 0.1)
				(type default)
			)
			(layer "F.Fab")
		)
		(fp_line
			(start -0.12065 -0.2794)
			(end 0.12065 -0.2794)
			(stroke
				(width 0.1)
				(type default)
			)
			(layer "F.Fab")
		)
		(fp_line
			(start 0.12065 -0.2794)
			(end 0.12065 -0.3048)
			(stroke
				(width 0.1)
				(type default)
			)
			(layer "F.Fab")
		)
		(fp_line
			(start 0.12065 -0.3048)
			(end 0.67945 -0.3048)
			(stroke
				(width 0.1)
				(type default)
			)
			(layer "F.Fab")
		)
		(fp_line
			(start 0.67945 -0.3048)
			(end 0.67945 0.3048)
			(stroke
				(width 0.1)
				(type default)
			)
			(layer "F.Fab")
		)
		(fp_line
			(start -0.67945 -0.305054)
			(end -0.12065 -0.305054)
			(stroke
				(width 0.1)
				(type default)
			)
			(layer "F.Fab")
		)
		(fp_line
			(start -0.12065 -0.305054)
			(end -0.12065 -0.2794)
			(stroke
				(width 0.1)
				(type default)
			)
			(layer "F.Fab")
		)
		(pad "1" smd circle
			(at -0.40005 0 270)
			(size 0 0)
			(layers "F.Cu" "F.Mask" "F.Paste")
			(net "LED_PWRGD_CPUPWRGD_GTL")
		)
		(pad "2" smd circle
			(at 0.40005 0 270)
			(size 0 0)
			(layers "F.Cu" "F.Mask" "F.Paste")
			(net "P3V3_AUX")
		)
	)
)
